(kicad_pcb
	(version 20260206)
	(generator "pcbnew")
	(generator_version "10.0")
	(general
		(thickness 1.6)
		(legacy_teardrops no)
	)
	(paper "A4")
	(title_block
		(title "01162023_DA0F0TEBIF0_F0T_Expander_BD_F_brd_V02_OCP.brd")
		(comment 1 "Grand Teton / footprints 1610-1615 of 9728")
	)
	(layers
		(0 "F.Cu" signal "TOP")
		(4 "In1.Cu" signal "GND")
		(6 "In2.Cu" signal "VCC")
		(8 "In3.Cu" signal "VCC1")
		(10 "In4.Cu" signal "GND1")
		(12 "In5.Cu" signal "IN1")
		(14 "In6.Cu" signal "GND2")
		(16 "In7.Cu" signal "IN2")
		(18 "In8.Cu" signal "GND3")
		(20 "In9.Cu" signal "IN3")
		(22 "In10.Cu" signal "GND4")
		(24 "In11.Cu" signal "IN4")
		(26 "In12.Cu" signal "GND5")
		(28 "In13.Cu" signal "IN5")
		(30 "In14.Cu" signal "GND6")
		(32 "In15.Cu" signal "IN6")
		(34 "In16.Cu" signal "GND7")
		(2 "B.Cu" signal "BOTTOM")
		(9 "F.Adhes" user "F.Adhesive")
		(11 "B.Adhes" user "B.Adhesive")
		(13 "F.Paste" user "Package Geometry/Pastemask Top")
		(15 "B.Paste" user "Package Geometry/Pastemask Bottom")
		(5 "F.SilkS" user "Ref Des/Silkscreen Top")
		(7 "B.SilkS" user "Ref Des/Silkscreen Bottom")
		(1 "F.Mask" user "Board Geometry/Soldermask Top")
		(3 "B.Mask" user "Board Geometry/Soldermask Bottom")
		(17 "Dwgs.User" user "User.Drawings")
		(19 "Cmts.User" user "User.Comments")
		(21 "Eco1.User" user "User.Eco1")
		(23 "Eco2.User" user "User.Eco2")
		(25 "Edge.Cuts" user "Board Geometry/Outline")
		(27 "Margin" user)
		(31 "F.CrtYd" user "Package Geometry/Place Bound Top")
		(29 "B.CrtYd" user "Package Geometry/Place Bound Bottom")
		(35 "F.Fab" user "Ref Des/Assembly Top")
		(33 "B.Fab" user "Ref Des/Assembly Bottom")
	)
	(footprint ""
		(layer "F.Cu")
		(at 237.722664 -206.51216 -90)
		(property "Reference" "C3609"
			(at 0 0 270)
			(layer "F.SilkS")
			(hide yes)
			(effects
				(font
					(size 1.27 1.27)
				)
			)
		)
		(property "Value" ""
			(at 0 0 270)
			(layer "F.Fab")
			(effects
				(font
					(size 1.27 1.27)
				)
			)
		)
		(duplicate_pad_numbers_are_jumpers no)
		(fp_line
			(start -0.7874 0.4064)
			(end -0.7874 -0.4064)
			(stroke
				(width 0.1524)
				(type default)
			)
			(layer "F.SilkS")
		)
		(fp_line
			(start 0.7874 0.4064)
			(end -0.7874 0.4064)
			(stroke
				(width 0.1524)
				(type default)
			)
			(layer "F.SilkS")
		)
		(fp_line
			(start -0.7874 -0.4064)
			(end 0.7874 -0.4064)
			(stroke
				(width 0.1524)
				(type default)
			)
			(layer "F.SilkS")
		)
		(fp_line
			(start 0.7874 -0.4064)
			(end 0.7874 0.4064)
			(stroke
				(width 0.1524)
				(type default)
			)
			(layer "F.SilkS")
		)
		(fp_line
			(start -0.67945 0.3048)
			(end -0.67945 -0.305054)
			(stroke
				(width 0.1)
				(type default)
			)
			(layer "F.Fab")
		)
		(fp_line
			(start -0.12065 0.3048)
			(end -0.67945 0.3048)
			(stroke
				(width 0.1)
				(type default)
			)
			(layer "F.Fab")
		)
		(fp_line
			(start 0.120396 0.3048)
			(end 0.120396 0.2794)
			(stroke
				(width 0.1)
				(type default)
			)
			(layer "F.Fab")
		)
		(fp_line
			(start 0.67945 0.3048)
			(end 0.120396 0.3048)
			(stroke
				(width 0.1)
				(type default)
			)
			(layer "F.Fab")
		)
		(fp_line
			(start -0.12065 0.2794)
			(end -0.12065 0.3048)
			(stroke
				(width 0.1)
				(type default)
			)
			(layer "F.Fab")
		)
		(fp_line
			(start 0.120396 0.2794)
			(end -0.12065 0.2794)
			(stroke
				(width 0.1)
				(type default)
			)
			(layer "F.Fab")
		)
		(fp_line
			(start -0.12065 -0.2794)
			(end 0.12065 -0.2794)
			(stroke
				(width 0.1)
				(type default)
			)
			(layer "F.Fab")
		)
		(fp_line
			(start 0.12065 -0.2794)
			(end 0.12065 -0.3048)
			(stroke
				(width 0.1)
				(type default)
			)
			(layer "F.Fab")
		)
		(fp_line
			(start 0.12065 -0.3048)
			(end 0.67945 -0.3048)
			(stroke
				(width 0.1)
				(type default)
			)
			(layer "F.Fab")
		)
		(fp_line
			(start 0.67945 -0.3048)
			(end 0.67945 0.3048)
			(stroke
				(width 0.1)
				(type default)
			)
			(layer "F.Fab")
		)
		(fp_line
			(start -0.67945 -0.305054)
			(end -0.12065 -0.305054)
			(stroke
				(width 0.1)
				(type default)
			)
			(layer "F.Fab")
		)
		(fp_line
			(start -0.12065 -0.305054)
			(end -0.12065 -0.2794)
			(stroke
				(width 0.1)
				(type default)
			)
			(layer "F.Fab")
		)
		(pad "1" smd circle
			(at -0.40005 0 270)
			(size 0 0)
			(layers "F.Cu" "F.Mask" "F.Paste")
			(net "P12V_AUX_SCALED")
		)
		(pad "2" smd circle
			(at 0.40005 0 270)
			(size 0 0)
			(layers "F.Cu" "F.Mask" "F.Paste")
			(net "GND")
		)
	)
	(footprint ""
		(layer "F.Cu")
		(at 437.514492 -311.227978 135)
		(property "Reference" "R1443"
			(at 0 0 135)
			(layer "F.SilkS")
			(hide yes)
			(effects
				(font
					(size 1.27 1.27)
				)
			)
		)
		(property "Value" ""
			(at 0 0 135)
			(layer "F.Fab")
			(effects
				(font
					(size 1.27 1.27)
				)
			)
		)
		(duplicate_pad_numbers_are_jumpers no)
		(fp_line
			(start 0.787389 -0.406267)
			(end 0.787389 0.406267)
			(stroke
				(width 0.1524)
				(type default)
			)
			(layer "F.SilkS")
		)
		(fp_line
			(start 0.787389 0.406267)
			(end -0.787389 0.406267)
			(stroke
				(width 0.1524)
				(type default)
			)
			(layer "F.SilkS")
		)
		(fp_line
			(start -0.787389 -0.406267)
			(end 0.787389 -0.406267)
			(stroke
				(width 0.1524)
				(type default)
			)
			(layer "F.SilkS")
		)
		(fp_line
			(start -0.787389 0.406267)
			(end -0.787389 -0.406267)
			(stroke
				(width 0.1524)
				(type default)
			)
			(layer "F.SilkS")
		)
		(fp_line
			(start 0.679446 -0.30479)
			(end 0.679446 0.30479)
			(stroke
				(width 0.1)
				(type default)
			)
			(layer "F.Fab")
		)
		(fp_line
			(start 0.120515 -0.30479)
			(end 0.679446 -0.30479)
			(stroke
				(width 0.1)
				(type default)
			)
			(layer "F.Fab")
		)
		(fp_line
			(start 0.120695 -0.279466)
			(end 0.120515 -0.30479)
			(stroke
				(width 0.1)
				(type default)
			)
			(layer "F.Fab")
		)
		(fp_line
			(start 0.679446 0.30479)
			(end 0.120515 0.30479)
			(stroke
				(width 0.1)
				(type default)
			)
			(layer "F.Fab")
		)
		(fp_line
			(start -0.120695 -0.304969)
			(end -0.120695 -0.279466)
			(stroke
				(width 0.1)
				(type default)
			)
			(layer "F.Fab")
		)
		(fp_line
			(start -0.120695 -0.279466)
			(end 0.120695 -0.279466)
			(stroke
				(width 0.1)
				(type default)
			)
			(layer "F.Fab")
		)
		(fp_line
			(start 0.120335 0.279466)
			(end -0.120695 0.279466)
			(stroke
				(width 0.1)
				(type default)
			)
			(layer "F.Fab")
		)
		(fp_line
			(start 0.120515 0.30479)
			(end 0.120335 0.279466)
			(stroke
				(width 0.1)
				(type default)
			)
			(layer "F.Fab")
		)
		(fp_line
			(start -0.679446 -0.305149)
			(end -0.120695 -0.304969)
			(stroke
				(width 0.1)
				(type default)
			)
			(layer "F.Fab")
		)
		(fp_line
			(start -0.120695 0.279466)
			(end -0.120515 0.30479)
			(stroke
				(width 0.1)
				(type default)
			)
			(layer "F.Fab")
		)
		(fp_line
			(start -0.120515 0.30479)
			(end -0.679446 0.30479)
			(stroke
				(width 0.1)
				(type default)
			)
			(layer "F.Fab")
		)
		(fp_line
			(start -0.679446 0.30479)
			(end -0.679446 -0.305149)
			(stroke
				(width 0.1)
				(type default)
			)
			(layer "F.Fab")
		)
		(pad "1" smd circle
			(at -0.40005 0 135)
			(size 0 0)
			(layers "F.Cu" "F.Mask" "F.Paste")
			(net "PEX3_SPARE0")
		)
		(pad "2" smd circle
			(at 0.40005 0 135)
			(size 0 0)
			(layers "F.Cu" "F.Mask" "F.Paste")
			(net "P1V8_PEX")
		)
	)
	(footprint ""
		(layer "F.Cu")
		(at 405.928068 -388.33679 -90)
		(property "Reference" "C4175"
			(at 0 0 270)
			(layer "F.SilkS")
			(hide yes)
			(effects
				(font
					(size 1.27 1.27)
				)
			)
		)
		(property "Value" ""
			(at 0 0 270)
			(layer "F.Fab")
			(effects
				(font
					(size 1.27 1.27)
				)
			)
		)
		(duplicate_pad_numbers_are_jumpers no)
		(fp_line
			(start -0.7874 0.4064)
			(end -0.7874 -0.4064)
			(stroke
				(width 0.1524)
				(type default)
			)
			(layer "F.SilkS")
		)
		(fp_line
			(start 0.7874 0.4064)
			(end -0.7874 0.4064)
			(stroke
				(width 0.1524)
				(type default)
			)
			(layer "F.SilkS")
		)
		(fp_line
			(start -0.7874 -0.4064)
			(end 0.7874 -0.4064)
			(stroke
				(width 0.1524)
				(type default)
			)
			(layer "F.SilkS")
		)
		(fp_line
			(start 0.7874 -0.4064)
			(end 0.7874 0.4064)
			(stroke
				(width 0.1524)
				(type default)
			)
			(layer "F.SilkS")
		)
		(fp_line
			(start -0.67945 0.3048)
			(end -0.67945 -0.305054)
			(stroke
				(width 0.1)
				(type default)
			)
			(layer "F.Fab")
		)
		(fp_line
			(start -0.12065 0.3048)
			(end -0.67945 0.3048)
			(stroke
				(width 0.1)
				(type default)
			)
			(layer "F.Fab")
		)
		(fp_line
			(start 0.120396 0.3048)
			(end 0.120396 0.2794)
			(stroke
				(width 0.1)
				(type default)
			)
			(layer "F.Fab")
		)
		(fp_line
			(start 0.67945 0.3048)
			(end 0.120396 0.3048)
			(stroke
				(width 0.1)
				(type default)
			)
			(layer "F.Fab")
		)
		(fp_line
			(start -0.12065 0.2794)
			(end -0.12065 0.3048)
			(stroke
				(width 0.1)
				(type default)
			)
			(layer "F.Fab")
		)
		(fp_line
			(start 0.120396 0.2794)
			(end -0.12065 0.2794)
			(stroke
				(width 0.1)
				(type default)
			)
			(layer "F.Fab")
		)
		(fp_line
			(start -0.12065 -0.2794)
			(end 0.12065 -0.2794)
			(stroke
				(width 0.1)
				(type default)
			)
			(layer "F.Fab")
		)
		(fp_line
			(start 0.12065 -0.2794)
			(end 0.12065 -0.3048)
			(stroke
				(width 0.1)
				(type default)
			)
			(layer "F.Fab")
		)
		(fp_line
			(start 0.12065 -0.3048)
			(end 0.67945 -0.3048)
			(stroke
				(width 0.1)
				(type default)
			)
			(layer "F.Fab")
		)
		(fp_line
			(start 0.67945 -0.3048)
			(end 0.67945 0.3048)
			(stroke
				(width 0.1)
				(type default)
			)
			(layer "F.Fab")
		)
		(fp_line
			(start -0.67945 -0.305054)
			(end -0.12065 -0.305054)
			(stroke
				(width 0.1)
				(type default)
			)
			(layer "F.Fab")
		)
		(fp_line
			(start -0.12065 -0.305054)
			(end -0.12065 -0.2794)
			(stroke
				(width 0.1)
				(type default)
			)
			(layer "F.Fab")
		)
		(pad "1" smd circle
			(at -0.40005 0 270)
			(size 0 0)
			(layers "F.Cu" "F.Mask" "F.Paste")
			(net "GND")
		)
		(pad "2" smd circle
			(at 0.40005 0 270)
			(size 0 0)
			(layers "F.Cu" "F.Mask" "F.Paste")
			(net "GPU_WP_HW_CTRL_N")
		)
	)
	(footprint ""
		(layer "F.Cu")
		(at 164.659056 -166.55288)
		(property "Reference" "U20"
			(at -4.740656 0.469646 0)
			(unlocked yes)
			(layer "F.SilkS")
			(effects
				(font
					(size 0.7874 0.5842)
					(thickness 0.1524)
				)
				(justify left)
			)
		)
		(property "Value" ""
			(at 0 0 0)
			(layer "F.Fab")
			(effects
				(font
					(size 1.27 1.27)
				)
			)
		)
		(duplicate_pad_numbers_are_jumpers no)
		(fp_line
			(start -1.684274 -1.074928)
			(end -0.381 -1.074928)
			(stroke
				(width 0.1524)
				(type default)
			)
			(layer "F.SilkS")
		)
		(fp_line
			(start -1.684274 1.074928)
			(end -1.684274 -1.074928)
			(stroke
				(width 0.1524)
				(type default)
			)
			(layer "F.SilkS")
		)
		(fp_line
			(start -0.381 -1.074928)
			(end 0 -0.625094)
			(stroke
				(width 0.1524)
				(type default)
			)
			(layer "F.SilkS")
		)
		(fp_line
			(start 0 -0.625094)
			(end 0.381 -1.074928)
			(stroke
				(width 0.1524)
				(type default)
			)
			(layer "F.SilkS")
		)
		(fp_line
			(start 0.381 -1.074928)
			(end 1.684274 -1.074928)
			(stroke
				(width 0.1524)
				(type default)
			)
			(layer "F.SilkS")
		)
		(fp_line
			(start 1.684274 -1.074928)
			(end 1.684274 1.074928)
			(stroke
				(width 0.1524)
				(type default)
			)
			(layer "F.SilkS")
		)
		(fp_line
			(start 1.684274 1.074928)
			(end -1.684274 1.074928)
			(stroke
				(width 0.1524)
				(type default)
			)
			(layer "F.SilkS")
		)
		(fp_poly
			(pts
				(xy -2.637282 -0.903986) (xy -2.637282 -0.395986) (xy -1.875282 -0.649986)
			)
			(stroke
				(width 0)
				(type default)
			)
			(fill yes)
			(layer "F.SilkS")
		)
		(fp_line
			(start -0.700024 -1.074928)
			(end -0.700024 1.074928)
			(stroke
				(width 0.1)
				(type default)
			)
			(layer "F.Fab")
		)
		(fp_line
			(start -0.700024 1.074928)
			(end 0.700024 1.074928)
			(stroke
				(width 0.1)
				(type default)
			)
			(layer "F.Fab")
		)
		(fp_line
			(start 0.700024 -1.074928)
			(end -0.700024 -1.074928)
			(stroke
				(width 0.1)
				(type default)
			)
			(layer "F.Fab")
		)
		(fp_line
			(start 0.700024 1.074928)
			(end 0.700024 -1.074928)
			(stroke
				(width 0.1)
				(type default)
			)
			(layer "F.Fab")
		)
		(fp_poly
			(pts
				(xy -2.637282 -0.903986) (xy -2.637282 -0.395986) (xy -1.875282 -0.649986)
			)
			(stroke
				(width 0)
				(type default)
			)
			(fill yes)
			(layer "F.Fab")
		)
		(pad "1" smd rect
			(at -1.100074 -0.649986 270)
			(size 0.4064 0.9144)
			(layers "F.Cu" "F.Mask" "F.Paste")
			(net "Net_8454")
		)
		(pad "2" smd rect
			(at -1.100074 0 270)
			(size 0.4064 0.9144)
			(layers "F.Cu" "F.Mask" "F.Paste")
			(net "RST_HP_NIC2_N")
		)
		(pad "3" smd rect
			(at -1.100074 0.649986 270)
			(size 0.4064 0.9144)
			(layers "F.Cu" "F.Mask" "F.Paste")
			(net "GND")
		)
		(pad "4" smd rect
			(at 1.100074 0.649986 270)
			(size 0.4064 0.9144)
			(layers "F.Cu" "F.Mask" "F.Paste")
			(net "RST_HP_NIC2_BUF_N")
		)
		(pad "5" smd rect
			(at 1.100074 -0.649986 270)
			(size 0.4064 0.9144)
			(layers "F.Cu" "F.Mask" "F.Paste")
			(net "P3V3_AUX")
		)
	)
	(footprint ""
		(layer "F.Cu")
		(at 258.467098 -57.332626)
		(property "Reference" "R6833"
			(at 0 0 0)
			(layer "F.SilkS")
			(hide yes)
			(effects
				(font
					(size 1.27 1.27)
				)
			)
		)
		(property "Value" ""
			(at 0 0 0)
			(layer "F.Fab")
			(effects
				(font
					(size 1.27 1.27)
				)
			)
		)
		(duplicate_pad_numbers_are_jumpers no)
		(fp_line
			(start -0.7874 -0.4064)
			(end 0.7874 -0.4064)
			(stroke
				(width 0.1524)
				(type default)
			)
			(layer "F.SilkS")
		)
		(fp_line
			(start -0.7874 0.4064)
			(end -0.7874 -0.4064)
			(stroke
				(width 0.1524)
				(type default)
			)
			(layer "F.SilkS")
		)
		(fp_line
			(start 0.7874 -0.4064)
			(end 0.7874 0.4064)
			(stroke
				(width 0.1524)
				(type default)
			)
			(layer "F.SilkS")
		)
		(fp_line
			(start 0.7874 0.4064)
			(end -0.7874 0.4064)
			(stroke
				(width 0.1524)
				(type default)
			)
			(layer "F.SilkS")
		)
		(fp_line
			(start -0.67945 -0.305054)
			(end -0.12065 -0.305054)
			(stroke
				(width 0.1)
				(type default)
			)
			(layer "F.Fab")
		)
		(fp_line
			(start -0.67945 0.3048)
			(end -0.67945 -0.305054)
			(stroke
				(width 0.1)
				(type default)
			)
			(layer "F.Fab")
		)
		(fp_line
			(start -0.12065 -0.305054)
			(end -0.12065 -0.2794)
			(stroke
				(width 0.1)
				(type default)
			)
			(layer "F.Fab")
		)
		(fp_line
			(start -0.12065 -0.2794)
			(end 0.12065 -0.2794)
			(stroke
				(width 0.1)
				(type default)
			)
			(layer "F.Fab")
		)
		(fp_line
			(start -0.12065 0.2794)
			(end -0.12065 0.3048)
			(stroke
				(width 0.1)
				(type default)
			)
			(layer "F.Fab")
		)
		(fp_line
			(start -0.12065 0.3048)
			(end -0.67945 0.3048)
			(stroke
				(width 0.1)
				(type default)
			)
			(layer "F.Fab")
		)
		(fp_line
			(start 0.120396 0.2794)
			(end -0.12065 0.2794)
			(stroke
				(width 0.1)
				(type default)
			)
			(layer "F.Fab")
		)
		(fp_line
			(start 0.120396 0.3048)
			(end 0.120396 0.2794)
			(stroke
				(width 0.1)
				(type default)
			)
			(layer "F.Fab")
		)
		(fp_line
			(start 0.12065 -0.3048)
			(end 0.67945 -0.3048)
			(stroke
				(width 0.1)
				(type default)
			)
			(layer "F.Fab")
		)
		(fp_line
			(start 0.12065 -0.2794)
			(end 0.12065 -0.3048)
			(stroke
				(width 0.1)
				(type default)
			)
			(layer "F.Fab")
		)
		(fp_line
			(start 0.67945 -0.3048)
			(end 0.67945 0.3048)
			(stroke
				(width 0.1)
				(type default)
			)
			(layer "F.Fab")
		)
		(fp_line
			(start 0.67945 0.3048)
			(end 0.120396 0.3048)
			(stroke
				(width 0.1)
				(type default)
			)
			(layer "F.Fab")
		)
		(pad "1" smd circle
			(at -0.40005 0)
			(size 0 0)
			(layers "F.Cu" "F.Mask" "F.Paste")
			(net "SSD8_PWR_EN_R")
		)
		(pad "2" smd circle
			(at 0.40005 0)
			(size 0 0)
			(layers "F.Cu" "F.Mask" "F.Paste")
			(net "GND")
		)
	)
	(footprint ""
		(layer "F.Cu")
		(at 123.67514 -98.320606 180)
		(property "Reference" "R1567"
			(at 0 0 180)
			(layer "F.SilkS")
			(hide yes)
			(effects
				(font
					(size 1.27 1.27)
				)
			)
		)
		(property "Value" ""
			(at 0 0 180)
			(layer "F.Fab")
			(effects
				(font
					(size 1.27 1.27)
				)
			)
		)
		(duplicate_pad_numbers_are_jumpers no)
		(fp_line
			(start 0.7874 0.4064)
			(end -0.7874 0.4064)
			(stroke
				(width 0.1524)
				(type default)
			)
			(layer "F.SilkS")
		)
		(fp_line
			(start 0.7874 -0.4064)
			(end 0.7874 0.4064)
			(stroke
				(width 0.1524)
				(type default)
			)
			(layer "F.SilkS")
		)
		(fp_line
			(start -0.7874 0.4064)
			(end -0.7874 -0.4064)
			(stroke
				(width 0.1524)
				(type default)
			)
			(layer "F.SilkS")
		)
		(fp_line
			(start -0.7874 -0.4064)
			(end 0.7874 -0.4064)
			(stroke
				(width 0.1524)
				(type default)
			)
			(layer "F.SilkS")
		)
		(fp_line
			(start 0.67945 0.3048)
			(end 0.120396 0.3048)
			(stroke
				(width 0.1)
				(type default)
			)
			(layer "F.Fab")
		)
		(fp_line
			(start 0.67945 -0.3048)
			(end 0.67945 0.3048)
			(stroke
				(width 0.1)
				(type default)
			)
			(layer "F.Fab")
		)
		(fp_line
			(start 0.12065 -0.2794)
			(end 0.12065 -0.3048)
			(stroke
				(width 0.1)
				(type default)
			)
			(layer "F.Fab")
		)
		(fp_line
			(start 0.12065 -0.3048)
			(end 0.67945 -0.3048)
			(stroke
				(width 0.1)
				(type default)
			)
			(layer "F.Fab")
		)
		(fp_line
			(start 0.120396 0.3048)
			(end 0.120396 0.2794)
			(stroke
				(width 0.1)
				(type default)
			)
			(layer "F.Fab")
		)
		(fp_line
			(start 0.120396 0.2794)
			(end -0.12065 0.2794)
			(stroke
				(width 0.1)
				(type default)
			)
			(layer "F.Fab")
		)
		(fp_line
			(start -0.12065 0.3048)
			(end -0.67945 0.3048)
			(stroke
				(width 0.1)
				(type default)
			)
			(layer "F.Fab")
		)
		(fp_line
			(start -0.12065 0.2794)
			(end -0.12065 0.3048)
			(stroke
				(width 0.1)
				(type default)
			)
			(layer "F.Fab")
		)
		(fp_line
			(start -0.12065 -0.2794)
			(end 0.12065 -0.2794)
			(stroke
				(width 0.1)
				(type default)
			)
			(layer "F.Fab")
		)
		(fp_line
			(start -0.12065 -0.305054)
			(end -0.12065 -0.2794)
			(stroke
				(width 0.1)
				(type default)
			)
			(layer "F.Fab")
		)
		(fp_line
			(start -0.67945 0.3048)
			(end -0.67945 -0.305054)
			(stroke
				(width 0.1)
				(type default)
			)
			(layer "F.Fab")
		)
		(fp_line
			(start -0.67945 -0.305054)
			(end -0.12065 -0.305054)
			(stroke
				(width 0.1)
				(type default)
			)
			(layer "F.Fab")
		)
		(pad "1" smd circle
			(at -0.40005 0 180)
			(size 0 0)
			(layers "F.Cu" "F.Mask" "F.Paste")
			(net "BIC_I2C9_SSD_MUX0_A1")
		)
		(pad "2" smd circle
			(at 0.40005 0 180)
			(size 0 0)
			(layers "F.Cu" "F.Mask" "F.Paste")
			(net "GND")
		)
	)
)
